# T6G (Grand Teton) — schematic netlist excerpt (pin names and nets, part order shuffled) for the footprints in the layout excerpt that follows; sources: Cadence DE-HDL packaged netlist, KiCad conversion of 04192023_DAF0TMB3IC0_F0TG_MB_C_brd_V02_OCP.brd

PR6800  Q_RES  2.2 1% CHIP  pkg 0402LF  page 360 : A = SW_P1V8_RETIMER_CPU0_BST ; B = SW_P1V8_RETIMER_CPU0_BST_R
R2939  Q_RES  33.2 1% CHIP  pkg 0402LF  page 81 : A = FM_GPU_HSC_EN ; B = FM_GPU_HSC_EN_R

(kicad_pcb
	(version 20260206)
	(generator "pcbnew")
	(generator_version "10.0")
	(general
		(thickness 1.6)
		(legacy_teardrops no)
	)
	(paper "A4")
	(title_block
		(title "04192023_DAF0TMB3IC0_F0TG_MB_C_brd_V02_OCP.brd")
		(comment 1 "Grand Teton / footprints 1009-1010 of 8354")
	)
	(layers
		(0 "F.Cu" signal "TOP")
		(4 "In1.Cu" signal "GND")
		(6 "In2.Cu" signal "IN1")
		(8 "In3.Cu" signal "GND1")
		(10 "In4.Cu" signal "IN2")
		(12 "In5.Cu" signal "GND2")
		(14 "In6.Cu" signal "IN3")
		(16 "In7.Cu" signal "GND3")
		(18 "In8.Cu" signal "VCC")
		(20 "In9.Cu" signal "VCC1")
		(22 "In10.Cu" signal "GND4")
		(24 "In11.Cu" signal "IN4")
		(26 "In12.Cu" signal "GND5")
		(28 "In13.Cu" signal "IN5")
		(30 "In14.Cu" signal "GND6")
		(32 "In15.Cu" signal "IN6")
		(34 "In16.Cu" signal "GND7")
		(2 "B.Cu" signal "BOTTOM")
		(9 "F.Adhes" user "F.Adhesive")
		(11 "B.Adhes" user "B.Adhesive")
		(13 "F.Paste" user "Package Geometry/Pastemask Top")
		(15 "B.Paste" user "Package Geometry/Pastemask Bottom")
		(5 "F.SilkS" user "Ref Des/Silkscreen Top")
		(7 "B.SilkS" user "Ref Des/Silkscreen Bottom")
		(1 "F.Mask" user "Board Geometry/Soldermask Top")
		(3 "B.Mask" user "Board Geometry/Soldermask Bottom")
		(17 "Dwgs.User" user "User.Drawings")
		(19 "Cmts.User" user "User.Comments")
		(21 "Eco1.User" user "User.Eco1")
		(23 "Eco2.User" user "User.Eco2")
		(25 "Edge.Cuts" user "Board Geometry/Outline")
		(27 "Margin" user)
		(31 "F.CrtYd" user "Package Geometry/Place Bound Top")
		(29 "B.CrtYd" user "Package Geometry/Place Bound Bottom")
		(35 "F.Fab" user "Ref Des/Assembly Top")
		(33 "B.Fab" user "Ref Des/Assembly Bottom")
	)
	(footprint ""
		(layer "F.Cu")
		(at 208.894426 -116.673376 180)
		(property "Reference" "R2939"
			(at 0 0 180)
			(layer "F.SilkS")
			(hide yes)
			(effects
				(font
					(size 1.27 1.27)
				)
			)
		)
		(property "Value" ""
			(at 0 0 180)
			(layer "F.Fab")
			(effects
				(font
					(size 1.27 1.27)
				)
			)
		)
		(duplicate_pad_numbers_are_jumpers no)
		(fp_line
			(start 0.7874 0.4064)
			(end -0.7874 0.4064)
			(stroke
				(width 0.1524)
				(type default)
			)
			(layer "F.SilkS")
		)
		(fp_line
			(start 0.7874 -0.4064)
			(end 0.7874 0.4064)
			(stroke
				(width 0.1524)
				(type default)
			)
			(layer "F.SilkS")
		)
		(fp_line
			(start -0.7874 0.4064)
			(end -0.7874 -0.4064)
			(stroke
				(width 0.1524)
				(type default)
			)
			(layer "F.SilkS")
		)
		(fp_line
			(start -0.7874 -0.4064)
			(end 0.7874 -0.4064)
			(stroke
				(width 0.1524)
				(type default)
			)
			(layer "F.SilkS")
		)
		(fp_line
			(start 0.67945 0.3048)
			(end 0.120396 0.3048)
			(stroke
				(width 0.1)
				(type default)
			)
			(layer "F.Fab")
		)
		(fp_line
			(start 0.67945 -0.3048)
			(end 0.67945 0.3048)
			(stroke
				(width 0.1)
				(type default)
			)
			(layer "F.Fab")
		)
		(fp_line
			(start 0.12065 -0.2794)
			(end 0.12065 -0.3048)
			(stroke
				(width 0.1)
				(type default)
			)
			(layer "F.Fab")
		)
		(fp_line
			(start 0.12065 -0.3048)
			(end 0.67945 -0.3048)
			(stroke
				(width 0.1)
				(type default)
			)
			(layer "F.Fab")
		)
		(fp_line
			(start 0.120396 0.3048)
			(end 0.120396 0.2794)
			(stroke
				(width 0.1)
				(type default)
			)
			(layer "F.Fab")
		)
		(fp_line
			(start 0.120396 0.2794)
			(end -0.12065 0.2794)
			(stroke
				(width 0.1)
				(type default)
			)
			(layer "F.Fab")
		)
		(fp_line
			(start -0.12065 0.3048)
			(end -0.67945 0.3048)
			(stroke
				(width 0.1)
				(type default)
			)
			(layer "F.Fab")
		)
		(fp_line
			(start -0.12065 0.2794)
			(end -0.12065 0.3048)
			(stroke
				(width 0.1)
				(type default)
			)
			(layer "F.Fab")
		)
		(fp_line
			(start -0.12065 -0.2794)
			(end 0.12065 -0.2794)
			(stroke
				(width 0.1)
				(type default)
			)
			(layer "F.Fab")
		)
		(fp_line
			(start -0.12065 -0.305054)
			(end -0.12065 -0.2794)
			(stroke
				(width 0.1)
				(type default)
			)
			(layer "F.Fab")
		)
		(fp_line
			(start -0.67945 0.3048)
			(end -0.67945 -0.305054)
			(stroke
				(width 0.1)
				(type default)
			)
			(layer "F.Fab")
		)
		(fp_line
			(start -0.67945 -0.305054)
			(end -0.12065 -0.305054)
			(stroke
				(width 0.1)
				(type default)
			)
			(layer "F.Fab")
		)
		(pad "1" smd circle
			(at -0.40005 0 180)
			(size 0 0)
			(layers "F.Cu" "F.Mask" "F.Paste")
			(net "FM_GPU_HSC_EN")
		)
		(pad "2" smd circle
			(at 0.40005 0 180)
			(size 0 0)
			(layers "F.Cu" "F.Mask" "F.Paste")
			(net "FM_GPU_HSC_EN_R")
		)
	)
	(footprint ""
		(layer "F.Cu")
		(at 240.771426 -294.597074 180)
		(property "Reference" "PR6800"
			(at 0 0 180)
			(layer "F.SilkS")
			(hide yes)
			(effects
				(font
					(size 1.27 1.27)
				)
			)
		)
		(property "Value" ""
			(at 0 0 180)
			(layer "F.Fab")
			(effects
				(font
					(size 1.27 1.27)
				)
			)
		)
		(duplicate_pad_numbers_are_jumpers no)
		(fp_line
			(start 0.7874 0.4064)
			(end -0.7874 0.4064)
			(stroke
				(width 0.1524)
				(type default)
			)
			(layer "F.SilkS")
		)
		(fp_line
			(start 0.7874 -0.4064)
			(end 0.7874 0.4064)
			(stroke
				(width 0.1524)
				(type default)
			)
			(layer "F.SilkS")
		)
		(fp_line
			(start -0.7874 0.4064)
			(end -0.7874 -0.4064)
			(stroke
				(width 0.1524)
				(type default)
			)
			(layer "F.SilkS")
		)
		(fp_line
			(start -0.7874 -0.4064)
			(end 0.7874 -0.4064)
			(stroke
				(width 0.1524)
				(type default)
			)
			(layer "F.SilkS")
		)
		(fp_line
			(start 0.67945 0.3048)
			(end 0.120396 0.3048)
			(stroke
				(width 0.1)
				(type default)
			)
			(layer "F.Fab")
		)
		(fp_line
			(start 0.67945 -0.3048)
			(end 0.67945 0.3048)
			(stroke
				(width 0.1)
				(type default)
			)
			(layer "F.Fab")
		)
		(fp_line
			(start 0.12065 -0.2794)
			(end 0.12065 -0.3048)
			(stroke
				(width 0.1)
				(type default)
			)
			(layer "F.Fab")
		)
		(fp_line
			(start 0.12065 -0.3048)
			(end 0.67945 -0.3048)
			(stroke
				(width 0.1)
				(type default)
			)
			(layer "F.Fab")
		)
		(fp_line
			(start 0.120396 0.3048)
			(end 0.120396 0.2794)
			(stroke
				(width 0.1)
				(type default)
			)
			(layer "F.Fab")
		)
		(fp_line
			(start 0.120396 0.2794)
			(end -0.12065 0.2794)
			(stroke
				(width 0.1)
				(type default)
			)
			(layer "F.Fab")
		)
		(fp_line
			(start -0.12065 0.3048)
			(end -0.67945 0.3048)
			(stroke
				(width 0.1)
				(type default)
			)
			(layer "F.Fab")
		)
		(fp_line
			(start -0.12065 0.2794)
			(end -0.12065 0.3048)
			(stroke
				(width 0.1)
				(type default)
			)
			(layer "F.Fab")
		)
		(fp_line
			(start -0.12065 -0.2794)
			(end 0.12065 -0.2794)
			(stroke
				(width 0.1)
				(type default)
			)
			(layer "F.Fab")
		)
		(fp_line
			(start -0.12065 -0.305054)
			(end -0.12065 -0.2794)
			(stroke
				(width 0.1)
				(type default)
			)
			(layer "F.Fab")
		)
		(fp_line
			(start -0.67945 0.3048)
			(end -0.67945 -0.305054)
			(stroke
				(width 0.1)
				(type default)
			)
			(layer "F.Fab")
		)
		(fp_line
			(start -0.67945 -0.305054)
			(end -0.12065 -0.305054)
			(stroke
				(width 0.1)
				(type default)
			)
			(layer "F.Fab")
		)
		(pad "1" smd circle
			(at -0.40005 0 180)
			(size 0 0)
			(layers "F.Cu" "F.Mask" "F.Paste")
			(net "SW_P1V8_RETIMER_CPU0_BST")
		)
		(pad "2" smd circle
			(at 0.40005 0 180)
			(size 0 0)
			(layers "F.Cu" "F.Mask" "F.Paste")
			(net "SW_P1V8_RETIMER_CPU0_BST_R")
		)
	)
)
